(kicad_pcb
	(version 20260206)
	(generator "pcbnew")
	(generator_version "10.0")
	(general
		(thickness 1.6)
		(legacy_teardrops no)
	)
	(paper "A4")
	(title_block
		(title "Bryce Canyon_SCC_16316-1_OCP.brd")
		(comment 1 "Bryce Canyon / footprints 1536-1543 of 1561")
	)
	(layers
		(0 "F.Cu" signal "TOP")
		(4 "In1.Cu" signal "L2GND")
		(6 "In2.Cu" signal "L3")
		(8 "In3.Cu" signal "L4VCC")
		(10 "In4.Cu" signal "L5VCC")
		(12 "In5.Cu" signal "L6")
		(14 "In6.Cu" signal "L7GND")
		(2 "B.Cu" signal "BOTTOM")
		(9 "F.Adhes" user "F.Adhesive")
		(11 "B.Adhes" user "B.Adhesive")
		(13 "F.Paste" user "Package Geometry/Pastemask Top")
		(15 "B.Paste" user "Package Geometry/Pastemask Bottom")
		(5 "F.SilkS" user "Ref Des/Silkscreen Top")
		(7 "B.SilkS" user "Ref Des/Silkscreen Bottom")
		(1 "F.Mask" user "Board Geometry/Soldermask Top")
		(3 "B.Mask" user "Board Geometry/Soldermask Bottom")
		(17 "Dwgs.User" user "User.Drawings")
		(19 "Cmts.User" user "User.Comments")
		(21 "Eco1.User" user "User.Eco1")
		(23 "Eco2.User" user "User.Eco2")
		(25 "Edge.Cuts" user "Board Geometry/Outline")
		(27 "Margin" user)
		(31 "F.CrtYd" user "Package Geometry/Place Bound Top")
		(29 "B.CrtYd" user "Package Geometry/Place Bound Bottom")
		(35 "F.Fab" user "Ref Des/Assembly Top")
		(33 "B.Fab" user "Ref Des/Assembly Bottom")
	)
	(footprint ""
		(layer "B.Cu")
		(at 101.843332 -66.789808 90)
		(property "Reference" "R380"
			(at 0 0 90)
			(layer "B.SilkS")
			(hide yes)
			(effects
				(font
					(size 1.27 1.27)
				)
				(justify mirror)
			)
		)
		(property "Value" "1KR2F-3-GP"
			(at -0.064008 -3.993896 90)
			(unlocked yes)
			(layer "B.Fab")
			(hide yes)
			(effects
				(font
					(size 1.016 1.016)
					(thickness 0.1524)
				)
				(justify mirror)
			)
		)
		(property "Device Type" "R402H16"
			(at -0.064008 -5.517896 90)
			(unlocked yes)
			(layer "B.Fab")
			(hide yes)
			(effects
				(font
					(size 1.016 1.016)
					(thickness 0.1524)
				)
				(justify mirror)
			)
		)
		(duplicate_pad_numbers_are_jumpers no)
		(fp_line
			(start 0.508 -0.9398)
			(end 0.508 0.9398)
			(stroke
				(width 0.1524)
				(type default)
			)
			(layer "B.SilkS")
		)
		(fp_line
			(start -0.508 -0.9398)
			(end 0.508 -0.9398)
			(stroke
				(width 0.1524)
				(type default)
			)
			(layer "B.SilkS")
		)
		(fp_rect
			(start 0.508 0.9398)
			(end -0.508 -0.9398)
			(stroke
				(width 0)
				(type default)
			)
			(fill no)
			(layer "B.CrtYd")
		)
		(fp_rect
			(start 0.508 0.9398)
			(end -0.508 -0.9398)
			(stroke
				(width 0)
				(type default)
			)
			(fill no)
			(layer "B.Fab")
		)
		(pad "1" smd custom
			(at 0 -0.4445 270)
			(size 0.1397 0.1397)
			(layers "B.Cu" "B.Mask" "B.Paste")
			(net "GND")
			(options
				(clearance outline)
				(anchor circle)
			)
			(primitives
				(gr_poly
					(pts
						(arc
							(start -0.1778 0.2794)
							(mid -0.249642 0.249642)
							(end -0.2794 0.1778)
						)
						(arc
							(start -0.2794 -0.1778)
							(mid -0.249642 -0.249642)
							(end -0.1778 -0.2794)
						)
						(arc
							(start 0.1778 -0.2794)
							(mid 0.249642 -0.249642)
							(end 0.2794 -0.1778)
						)
						(arc
							(start 0.2794 0.1778)
							(mid 0.249642 0.249642)
							(end 0.1778 0.2794)
						)
					)
					(width 0)
					(fill yes)
				)
			)
		)
		(pad "2" smd custom
			(at 0 0.4445 270)
			(size 0.1397 0.1397)
			(layers "B.Cu" "B.Mask" "B.Paste")
			(net "DDR_BZ")
			(options
				(clearance outline)
				(anchor circle)
			)
			(primitives
				(gr_poly
					(pts
						(arc
							(start -0.1778 0.2794)
							(mid -0.249642 0.249642)
							(end -0.2794 0.1778)
						)
						(arc
							(start -0.2794 -0.1778)
							(mid -0.249642 -0.249642)
							(end -0.1778 -0.2794)
						)
						(arc
							(start 0.1778 -0.2794)
							(mid 0.249642 -0.249642)
							(end 0.2794 -0.1778)
						)
						(arc
							(start 0.2794 0.1778)
							(mid 0.249642 0.249642)
							(end 0.1778 0.2794)
						)
					)
					(width 0)
					(fill yes)
				)
			)
		)
	)
	(footprint ""
		(layer "B.Cu")
		(at 166.863776 -45.314616)
		(property "Reference" "C455"
			(at 0 0 0)
			(layer "B.SilkS")
			(hide yes)
			(effects
				(font
					(size 1.27 1.27)
				)
				(justify mirror)
			)
		)
		(property "Value" "SCD1U6D3V1KX-GP"
			(at 2.8321 -1.7399 0)
			(unlocked yes)
			(layer "B.Fab")
			(hide yes)
			(effects
				(font
					(size 1.016 1.016)
					(thickness 0.1524)
				)
				(justify mirror)
			)
		)
		(property "Device Type" "C0201H13"
			(at 2.8321 -3.2639 0)
			(unlocked yes)
			(layer "B.Fab")
			(hide yes)
			(effects
				(font
					(size 1.016 1.016)
					(thickness 0.1524)
				)
				(justify mirror)
			)
		)
		(duplicate_pad_numbers_are_jumpers no)
		(fp_rect
			(start 0.2794 0.6477)
			(end -0.2794 -0.6477)
			(stroke
				(width 0)
				(type default)
			)
			(fill no)
			(layer "B.CrtYd")
		)
		(fp_rect
			(start 0.2794 0.6477)
			(end -0.2794 -0.6477)
			(stroke
				(width 0)
				(type default)
			)
			(fill no)
			(layer "B.Fab")
		)
		(pad "1" smd custom
			(at 0 -0.2794 180)
			(size 0.0762 0.0762)
			(layers "B.Cu" "B.Mask" "B.Paste")
			(net "P1V8_C")
			(options
				(clearance outline)
				(anchor circle)
			)
			(primitives
				(gr_poly
					(pts
						(arc
							(start 0.1524 0.127)
							(mid 0.137521 0.162921)
							(end 0.1016 0.1778)
						)
						(arc
							(start -0.1016 0.1778)
							(mid -0.137521 0.162921)
							(end -0.1524 0.127)
						)
						(arc
							(start -0.1524 -0.127)
							(mid -0.137521 -0.162921)
							(end -0.1016 -0.1778)
						)
						(arc
							(start 0.1016 -0.1778)
							(mid 0.137521 -0.162921)
							(end 0.1524 -0.127)
						)
					)
					(width 0)
					(fill yes)
				)
			)
		)
		(pad "2" smd custom
			(at 0 0.2794 180)
			(size 0.0762 0.0762)
			(layers "B.Cu" "B.Mask" "B.Paste")
			(net "GND")
			(options
				(clearance outline)
				(anchor circle)
			)
			(primitives
				(gr_poly
					(pts
						(arc
							(start 0.1524 0.127)
							(mid 0.137521 0.162921)
							(end 0.1016 0.1778)
						)
						(arc
							(start -0.1016 0.1778)
							(mid -0.137521 0.162921)
							(end -0.1524 0.127)
						)
						(arc
							(start -0.1524 -0.127)
							(mid -0.137521 -0.162921)
							(end -0.1016 -0.1778)
						)
						(arc
							(start 0.1016 -0.1778)
							(mid 0.137521 -0.162921)
							(end 0.1524 -0.127)
						)
					)
					(width 0)
					(fill yes)
				)
			)
		)
	)
	(footprint ""
		(layer "B.Cu")
		(at 137.4648 -68.3514 -90)
		(property "Reference" "C17"
			(at 0 0 90)
			(layer "B.SilkS")
			(hide yes)
			(effects
				(font
					(size 1.27 1.27)
				)
				(justify mirror)
			)
		)
		(property "Value" "SCD01U16V1KX-GP"
			(at 2.8321 -1.7399 270)
			(unlocked yes)
			(layer "B.Fab")
			(hide yes)
			(effects
				(font
					(size 1.016 1.016)
					(thickness 0.1524)
				)
				(justify mirror)
			)
		)
		(property "Device Type" "C0201H13"
			(at 2.8321 -3.2639 270)
			(unlocked yes)
			(layer "B.Fab")
			(hide yes)
			(effects
				(font
					(size 1.016 1.016)
					(thickness 0.1524)
				)
				(justify mirror)
			)
		)
		(duplicate_pad_numbers_are_jumpers no)
		(fp_rect
			(start 0.2794 0.6477)
			(end -0.2794 -0.6477)
			(stroke
				(width 0)
				(type default)
			)
			(fill no)
			(layer "B.CrtYd")
		)
		(fp_rect
			(start 0.2794 0.6477)
			(end -0.2794 -0.6477)
			(stroke
				(width 0)
				(type default)
			)
			(fill no)
			(layer "B.Fab")
		)
		(pad "1" smd custom
			(at 0 -0.2794 90)
			(size 0.0762 0.0762)
			(layers "B.Cu" "B.Mask" "B.Paste")
			(net "PHY_DPB_TO_SCC_3_DP")
			(options
				(clearance outline)
				(anchor circle)
			)
			(primitives
				(gr_poly
					(pts
						(arc
							(start 0.1524 0.127)
							(mid 0.137521 0.162921)
							(end 0.1016 0.1778)
						)
						(arc
							(start -0.1016 0.1778)
							(mid -0.137521 0.162921)
							(end -0.1524 0.127)
						)
						(arc
							(start -0.1524 -0.127)
							(mid -0.137521 -0.162921)
							(end -0.1016 -0.1778)
						)
						(arc
							(start 0.1016 -0.1778)
							(mid 0.137521 -0.162921)
							(end 0.1524 -0.127)
						)
					)
					(width 0)
					(fill yes)
				)
			)
		)
		(pad "2" smd custom
			(at 0 0.2794 90)
			(size 0.0762 0.0762)
			(layers "B.Cu" "B.Mask" "B.Paste")
			(net "PHY_DPB_TO_SCC_C_3_DP")
			(options
				(clearance outline)
				(anchor circle)
			)
			(primitives
				(gr_poly
					(pts
						(arc
							(start 0.1524 0.127)
							(mid 0.137521 0.162921)
							(end 0.1016 0.1778)
						)
						(arc
							(start -0.1016 0.1778)
							(mid -0.137521 0.162921)
							(end -0.1524 0.127)
						)
						(arc
							(start -0.1524 -0.127)
							(mid -0.137521 -0.162921)
							(end -0.1016 -0.1778)
						)
						(arc
							(start 0.1016 -0.1778)
							(mid 0.137521 -0.162921)
							(end 0.1524 -0.127)
						)
					)
					(width 0)
					(fill yes)
				)
			)
		)
	)
	(footprint ""
		(layer "B.Cu")
		(at 96.258634 -84.53374 -90)
		(property "Reference" "C114"
			(at 0 0 90)
			(layer "B.SilkS")
			(hide yes)
			(effects
				(font
					(size 1.27 1.27)
				)
				(justify mirror)
			)
		)
		(property "Value" "SCD1U16V2KX-3GP"
			(at -1.1811 -2.7051 270)
			(unlocked yes)
			(layer "B.Fab")
			(hide yes)
			(effects
				(font
					(size 1.016 1.016)
					(thickness 0.1524)
				)
				(justify mirror)
			)
		)
		(property "Device Type" "C402H22"
			(at -1.1811 -4.2291 270)
			(unlocked yes)
			(layer "B.Fab")
			(hide yes)
			(effects
				(font
					(size 1.016 1.016)
					(thickness 0.1524)
				)
				(justify mirror)
			)
		)
		(duplicate_pad_numbers_are_jumpers no)
		(fp_rect
			(start 0.4318 0.9525)
			(end -0.4318 -0.9525)
			(stroke
				(width 0)
				(type default)
			)
			(fill no)
			(layer "B.CrtYd")
		)
		(fp_rect
			(start 0.4318 0.9525)
			(end -0.4318 -0.9525)
			(stroke
				(width 0)
				(type default)
			)
			(fill no)
			(layer "B.Fab")
		)
		(pad "1" smd custom
			(at 0 -0.4445 90)
			(size 0.1524 0.1524)
			(layers "B.Cu" "B.Mask" "B.Paste")
			(net "P1V8_E")
			(options
				(clearance outline)
				(anchor circle)
			)
			(primitives
				(gr_poly
					(pts
						(arc
							(start 0.3048 0.2032)
							(mid 0.275042 0.275042)
							(end 0.2032 0.3048)
						)
						(arc
							(start -0.2032 0.3048)
							(mid -0.275042 0.275042)
							(end -0.3048 0.2032)
						)
						(arc
							(start -0.3048 -0.2032)
							(mid -0.275042 -0.275042)
							(end -0.2032 -0.3048)
						)
						(arc
							(start 0.2032 -0.3048)
							(mid 0.275042 -0.275042)
							(end 0.3048 -0.2032)
						)
					)
					(width 0)
					(fill yes)
				)
			)
		)
		(pad "2" smd custom
			(at 0 0.4445 90)
			(size 0.1524 0.1524)
			(layers "B.Cu" "B.Mask" "B.Paste")
			(net "GND")
			(options
				(clearance outline)
				(anchor circle)
			)
			(primitives
				(gr_poly
					(pts
						(arc
							(start 0.3048 0.2032)
							(mid 0.275042 0.275042)
							(end 0.2032 0.3048)
						)
						(arc
							(start -0.2032 0.3048)
							(mid -0.275042 0.275042)
							(end -0.3048 0.2032)
						)
						(arc
							(start -0.3048 -0.2032)
							(mid -0.275042 -0.275042)
							(end -0.2032 -0.3048)
						)
						(arc
							(start 0.2032 -0.3048)
							(mid 0.275042 -0.275042)
							(end 0.3048 -0.2032)
						)
					)
					(width 0)
					(fill yes)
				)
			)
		)
	)
	(footprint ""
		(layer "B.Cu")
		(at 165.558978 -20.583144)
		(property "Reference" "C312"
			(at 0 0 0)
			(layer "B.SilkS")
			(hide yes)
			(effects
				(font
					(size 1.27 1.27)
				)
				(justify mirror)
			)
		)
		(property "Value" "SCD22U10V1KX-GP"
			(at 2.8321 -1.7399 0)
			(unlocked yes)
			(layer "B.Fab")
			(hide yes)
			(effects
				(font
					(size 1.016 1.016)
					(thickness 0.1524)
				)
				(justify mirror)
			)
		)
		(property "Device Type" "C0201H13"
			(at 2.8321 -3.2639 0)
			(unlocked yes)
			(layer "B.Fab")
			(hide yes)
			(effects
				(font
					(size 1.016 1.016)
					(thickness 0.1524)
				)
				(justify mirror)
			)
		)
		(duplicate_pad_numbers_are_jumpers no)
		(fp_rect
			(start 0.2794 0.6477)
			(end -0.2794 -0.6477)
			(stroke
				(width 0)
				(type default)
			)
			(fill no)
			(layer "B.CrtYd")
		)
		(fp_rect
			(start 0.2794 0.6477)
			(end -0.2794 -0.6477)
			(stroke
				(width 0)
				(type default)
			)
			(fill no)
			(layer "B.Fab")
		)
		(pad "1" smd custom
			(at 0 -0.2794 180)
			(size 0.0762 0.0762)
			(layers "B.Cu" "B.Mask" "B.Paste")
			(net "PCIE_SCC_TO_COMP_C_0_DN")
			(options
				(clearance outline)
				(anchor circle)
			)
			(primitives
				(gr_poly
					(pts
						(arc
							(start 0.1524 0.127)
							(mid 0.137521 0.162921)
							(end 0.1016 0.1778)
						)
						(arc
							(start -0.1016 0.1778)
							(mid -0.137521 0.162921)
							(end -0.1524 0.127)
						)
						(arc
							(start -0.1524 -0.127)
							(mid -0.137521 -0.162921)
							(end -0.1016 -0.1778)
						)
						(arc
							(start 0.1016 -0.1778)
							(mid 0.137521 -0.162921)
							(end 0.1524 -0.127)
						)
					)
					(width 0)
					(fill yes)
				)
			)
		)
		(pad "2" smd custom
			(at 0 0.2794 180)
			(size 0.0762 0.0762)
			(layers "B.Cu" "B.Mask" "B.Paste")
			(net "PCIE_SCC_TO_COMP_0_DN")
			(options
				(clearance outline)
				(anchor circle)
			)
			(primitives
				(gr_poly
					(pts
						(arc
							(start 0.1524 0.127)
							(mid 0.137521 0.162921)
							(end 0.1016 0.1778)
						)
						(arc
							(start -0.1016 0.1778)
							(mid -0.137521 0.162921)
							(end -0.1524 0.127)
						)
						(arc
							(start -0.1524 -0.127)
							(mid -0.137521 -0.162921)
							(end -0.1016 -0.1778)
						)
						(arc
							(start 0.1016 -0.1778)
							(mid 0.137521 -0.162921)
							(end 0.1524 -0.127)
						)
					)
					(width 0)
					(fill yes)
				)
			)
		)
	)
	(footprint ""
		(layer "B.Cu")
		(at 120.542558 -86.65591 180)
		(property "Reference" "R404"
			(at 0 0 0)
			(layer "B.SilkS")
			(hide yes)
			(effects
				(font
					(size 1.27 1.27)
				)
				(justify mirror)
			)
		)
		(property "Value" "10KR2F-2-GP"
			(at -0.064008 -3.993896 180)
			(unlocked yes)
			(layer "B.Fab")
			(hide yes)
			(effects
				(font
					(size 1.016 1.016)
					(thickness 0.1524)
				)
				(justify mirror)
			)
		)
		(property "Device Type" "R402H16"
			(at -0.064008 -5.517896 180)
			(unlocked yes)
			(layer "B.Fab")
			(hide yes)
			(effects
				(font
					(size 1.016 1.016)
					(thickness 0.1524)
				)
				(justify mirror)
			)
		)
		(duplicate_pad_numbers_are_jumpers no)
		(fp_line
			(start 0.508 -0.9398)
			(end 0.508 0.9398)
			(stroke
				(width 0.1524)
				(type default)
			)
			(layer "B.SilkS")
		)
		(fp_line
			(start -0.508 -0.9398)
			(end 0.508 -0.9398)
			(stroke
				(width 0.1524)
				(type default)
			)
			(layer "B.SilkS")
		)
		(fp_rect
			(start 0.508 0.9398)
			(end -0.508 -0.9398)
			(stroke
				(width 0)
				(type default)
			)
			(fill no)
			(layer "B.CrtYd")
		)
		(fp_rect
			(start 0.508 0.9398)
			(end -0.508 -0.9398)
			(stroke
				(width 0)
				(type default)
			)
			(fill no)
			(layer "B.Fab")
		)
		(pad "1" smd custom
			(at 0 -0.4445)
			(size 0.1397 0.1397)
			(layers "B.Cu" "B.Mask" "B.Paste")
			(net "SLOT_ID_1")
			(options
				(clearance outline)
				(anchor circle)
			)
			(primitives
				(gr_poly
					(pts
						(arc
							(start -0.1778 0.2794)
							(mid -0.249642 0.249642)
							(end -0.2794 0.1778)
						)
						(arc
							(start -0.2794 -0.1778)
							(mid -0.249642 -0.249642)
							(end -0.1778 -0.2794)
						)
						(arc
							(start 0.1778 -0.2794)
							(mid 0.249642 -0.249642)
							(end 0.2794 -0.1778)
						)
						(arc
							(start 0.2794 0.1778)
							(mid 0.249642 0.249642)
							(end 0.1778 0.2794)
						)
					)
					(width 0)
					(fill yes)
				)
			)
		)
		(pad "2" smd custom
			(at 0 0.4445)
			(size 0.1397 0.1397)
			(layers "B.Cu" "B.Mask" "B.Paste")
			(net "P1V8_E")
			(options
				(clearance outline)
				(anchor circle)
			)
			(primitives
				(gr_poly
					(pts
						(arc
							(start -0.1778 0.2794)
							(mid -0.249642 0.249642)
							(end -0.2794 0.1778)
						)
						(arc
							(start -0.2794 -0.1778)
							(mid -0.249642 -0.249642)
							(end -0.1778 -0.2794)
						)
						(arc
							(start 0.1778 -0.2794)
							(mid 0.249642 -0.249642)
							(end 0.2794 -0.1778)
						)
						(arc
							(start 0.2794 0.1778)
							(mid 0.249642 0.249642)
							(end 0.1778 0.2794)
						)
					)
					(width 0)
					(fill yes)
				)
			)
		)
	)
	(footprint ""
		(layer "B.Cu")
		(at 123.7996 -39.4716 180)
		(property "Reference" "C53"
			(at 0 0 0)
			(layer "B.SilkS")
			(hide yes)
			(effects
				(font
					(size 1.27 1.27)
				)
				(justify mirror)
			)
		)
		(property "Value" "SCD01U16V1KX-GP"
			(at 2.8321 -1.7399 180)
			(unlocked yes)
			(layer "B.Fab")
			(hide yes)
			(effects
				(font
					(size 1.016 1.016)
					(thickness 0.1524)
				)
				(justify mirror)
			)
		)
		(property "Device Type" "C0201H13"
			(at 2.8321 -3.2639 180)
			(unlocked yes)
			(layer "B.Fab")
			(hide yes)
			(effects
				(font
					(size 1.016 1.016)
					(thickness 0.1524)
				)
				(justify mirror)
			)
		)
		(duplicate_pad_numbers_are_jumpers no)
		(fp_rect
			(start 0.2794 0.6477)
			(end -0.2794 -0.6477)
			(stroke
				(width 0)
				(type default)
			)
			(fill no)
			(layer "B.CrtYd")
		)
		(fp_rect
			(start 0.2794 0.6477)
			(end -0.2794 -0.6477)
			(stroke
				(width 0)
				(type default)
			)
			(fill no)
			(layer "B.Fab")
		)
		(pad "1" smd custom
			(at 0 -0.2794)
			(size 0.0762 0.0762)
			(layers "B.Cu" "B.Mask" "B.Paste")
			(net "PHY_DPB_TO_SCC_37_DP")
			(options
				(clearance outline)
				(anchor circle)
			)
			(primitives
				(gr_poly
					(pts
						(arc
							(start 0.1524 0.127)
							(mid 0.137521 0.162921)
							(end 0.1016 0.1778)
						)
						(arc
							(start -0.1016 0.1778)
							(mid -0.137521 0.162921)
							(end -0.1524 0.127)
						)
						(arc
							(start -0.1524 -0.127)
							(mid -0.137521 -0.162921)
							(end -0.1016 -0.1778)
						)
						(arc
							(start 0.1016 -0.1778)
							(mid 0.137521 -0.162921)
							(end 0.1524 -0.127)
						)
					)
					(width 0)
					(fill yes)
				)
			)
		)
		(pad "2" smd custom
			(at 0 0.2794)
			(size 0.0762 0.0762)
			(layers "B.Cu" "B.Mask" "B.Paste")
			(net "PHY_DPB_TO_SCC_C_37_DP")
			(options
				(clearance outline)
				(anchor circle)
			)
			(primitives
				(gr_poly
					(pts
						(arc
							(start 0.1524 0.127)
							(mid 0.137521 0.162921)
							(end 0.1016 0.1778)
						)
						(arc
							(start -0.1016 0.1778)
							(mid -0.137521 0.162921)
							(end -0.1524 0.127)
						)
						(arc
							(start -0.1524 -0.127)
							(mid -0.137521 -0.162921)
							(end -0.1016 -0.1778)
						)
						(arc
							(start 0.1016 -0.1778)
							(mid 0.137521 -0.162921)
							(end 0.1524 -0.127)
						)
					)
					(width 0)
					(fill yes)
				)
			)
		)
	)
	(footprint ""
		(layer "B.Cu")
		(at 42.910252 -106.13898 -90)
		(property "Reference" "C709"
			(at 0 0 90)
			(layer "B.SilkS")
			(hide yes)
			(effects
				(font
					(size 1.27 1.27)
				)
				(justify mirror)
			)
		)
		(property "Value" "SC10U16V5KX-7-GP-U"
			(at 0.0762 -6.1214 270)
			(unlocked yes)
			(layer "B.Fab")
			(hide yes)
			(effects
				(font
					(size 1.016 1.016)
					(thickness 0.1524)
				)
				(justify mirror)
			)
		)
		(property "Device Type" "C805H58"
			(at 0.0762 -8.1534 270)
			(unlocked yes)
			(layer "B.Fab")
			(hide yes)
			(effects
				(font
					(size 1.016 1.016)
					(thickness 0.1524)
				)
				(justify mirror)
			)
		)
		(duplicate_pad_numbers_are_jumpers no)
		(fp_line
			(start -0.635 0)
			(end 0.635 0)
			(stroke
				(width 0.508)
				(type default)
			)
			(layer "B.SilkS")
		)
		(fp_rect
			(start 0.9652 1.778)
			(end -0.9652 -1.778)
			(stroke
				(width 0)
				(type default)
			)
			(fill no)
			(layer "B.CrtYd")
		)
		(fp_poly
			(pts
				(xy 0.9652 -1.778) (xy -0.9652 -1.778) (xy -0.9652 1.778) (xy 0.9652 1.778)
			)
			(stroke
				(width 0)
				(type default)
			)
			(fill no)
			(layer "B.Fab")
		)
		(pad "1" smd rect
			(at 0 -0.9652 90)
			(size 1.397 1.143)
			(layers "B.Cu" "B.Mask" "B.Paste")
			(net "P12V_STBY_SCC")
		)
		(pad "2" smd rect
			(at 0 0.9652 90)
			(size 1.397 1.143)
			(layers "B.Cu" "B.Mask" "B.Paste")
			(net "GND")
		)
	)
)
